FILE_TYPE = MULTI_PHYS_TABLE;

PART 'QS3VH257QG8'

{========================================================================================}
:PACK_TYPE | VALUE         | MATERIAL | PART_NUMBER    = STANDARD | LIFECYCLE      | PART_NUMBER   | JEDEC_TYPE              | CLASS | DESCRIPTION                      | HEIGHT   | COMPONENT_TYPE | LEAD_LENGTH | DFM_EXCLUSION | DAY        ;
{========================================================================================}
 'SMLF'    | 'QS3VH257QG8' | 'IC'     | 'AL000257W24'(!) = ''       | ''               | 'AL000257W24' |'QSOP16_0-635_4-89X3-9'| 'IC'  | 'IC OTHER(16P)QS3VH257QG8(QSOP)' | '.068IN' | 'SMALLSMT'     | ''          | ''            | '20210902'
 'SMLF'    | 'QS3VH257QG8' | 'EMPTY'  | 'AL000257W24'(!) = ''       | ''               | 'AL000257W24' |'QSOP16_0-635_4-89X3-9'| 'IO'  | 'IC OTHER(16P)QS3VH257QG8(QSOP)' | '.068IN' | 'SMALLSMT'     | ''          | ''            | '20210902'

END_PART

END.

